# S9S_MB_2U (Grand Teton) — schematic netlist excerpt (pin names and nets, part order shuffled) for the footprints in the layout excerpt that follows; sources: Cadence DE-HDL packaged netlist, KiCad conversion of 03242023_DA0F0TMBIJ0_F0T_Motherboard_J_brd_V01_OCP.brd

R3201  Q_RES  22 1% CHIP  pkg 0402LF  page 207 : A = CLK_100M_OCP_V3_2_D_R_DN ; B = CLK_100M_OCP_V3_2_D_DN
R3317  Q_RES  4.7K 5% EMPTY  pkg 0402LF  page 151 : A = P3V3_AUX ; B = GPU_FPGA_RST_R1_BUF_N

U330  APX80929SAG7  APX809-29SAG-7 IC  pkg SOT23_123XI  page 260
  GND  = GND
  RESET_L  = PWRGD_P3V3_R1
  VCC  = P3V3

(kicad_pcb
	(version 20260206)
	(generator "pcbnew")
	(generator_version "10.0")
	(general
		(thickness 1.6)
		(legacy_teardrops no)
	)
	(paper "A4")
	(title_block
		(title "03242023_DA0F0TMBIJ0_F0T_Motherboard_J_brd_V01_OCP.brd")
		(comment 1 "Grand Teton / footprints 159-161 of 6105")
	)
	(layers
		(0 "F.Cu" signal "TOP")
		(4 "In1.Cu" signal "GND")
		(6 "In2.Cu" signal "IN1")
		(8 "In3.Cu" signal "GND1")
		(10 "In4.Cu" signal "IN2")
		(12 "In5.Cu" signal "GND2")
		(14 "In6.Cu" signal "IN3")
		(16 "In7.Cu" signal "GND3")
		(18 "In8.Cu" signal "VCC")
		(20 "In9.Cu" signal "VCC1")
		(22 "In10.Cu" signal "GND4")
		(24 "In11.Cu" signal "IN4")
		(26 "In12.Cu" signal "GND5")
		(28 "In13.Cu" signal "IN5")
		(30 "In14.Cu" signal "GND6")
		(32 "In15.Cu" signal "IN6")
		(34 "In16.Cu" signal "GND7")
		(2 "B.Cu" signal "BOTTOM")
		(9 "F.Adhes" user "F.Adhesive")
		(11 "B.Adhes" user "B.Adhesive")
		(13 "F.Paste" user "Package Geometry/Pastemask Top")
		(15 "B.Paste" user "Package Geometry/Pastemask Bottom")
		(5 "F.SilkS" user "Ref Des/Silkscreen Top")
		(7 "B.SilkS" user "Ref Des/Silkscreen Bottom")
		(1 "F.Mask" user "Board Geometry/Soldermask Top")
		(3 "B.Mask" user "Board Geometry/Soldermask Bottom")
		(17 "Dwgs.User" user "User.Drawings")
		(19 "Cmts.User" user "User.Comments")
		(21 "Eco1.User" user "User.Eco1")
		(23 "Eco2.User" user "User.Eco2")
		(25 "Edge.Cuts" user "Board Geometry/Outline")
		(27 "Margin" user)
		(31 "F.CrtYd" user "Package Geometry/Place Bound Top")
		(29 "B.CrtYd" user "Package Geometry/Place Bound Bottom")
		(35 "F.Fab" user "Ref Des/Assembly Top")
		(33 "B.Fab" user "Ref Des/Assembly Bottom")
	)
	(footprint ""
		(layer "F.Cu")
		(at 422.02354 -52.16652)
		(property "Reference" "U330"
			(at -1.905 -2.174748 0)
			(unlocked yes)
			(layer "F.SilkS")
			(effects
				(font
					(size 0.7874 0.5842)
					(thickness 0.1524)
				)
				(justify left)
			)
		)
		(property "Value" ""
			(at 0 0 0)
			(layer "F.Fab")
			(effects
				(font
					(size 1.27 1.27)
				)
			)
		)
		(duplicate_pad_numbers_are_jumpers no)
		(fp_line
			(start -1.759712 -1.500124)
			(end 1.759712 -1.500124)
			(stroke
				(width 0.1524)
				(type default)
			)
			(layer "F.SilkS")
		)
		(fp_line
			(start -1.759712 1.500124)
			(end -1.759712 -1.500124)
			(stroke
				(width 0.1524)
				(type default)
			)
			(layer "F.SilkS")
		)
		(fp_line
			(start 1.759712 -1.500124)
			(end 1.759712 1.500124)
			(stroke
				(width 0.1524)
				(type default)
			)
			(layer "F.SilkS")
		)
		(fp_line
			(start 1.759712 1.500124)
			(end -1.759712 1.500124)
			(stroke
				(width 0.1524)
				(type default)
			)
			(layer "F.SilkS")
		)
		(fp_line
			(start -0.700024 -1.500124)
			(end 0.700024 -1.500124)
			(stroke
				(width 0.1)
				(type default)
			)
			(layer "F.Fab")
		)
		(fp_line
			(start -0.700024 1.500124)
			(end -0.700024 -1.500124)
			(stroke
				(width 0.1)
				(type default)
			)
			(layer "F.Fab")
		)
		(fp_line
			(start 0.700024 -1.500124)
			(end 0.700024 1.500124)
			(stroke
				(width 0.1)
				(type default)
			)
			(layer "F.Fab")
		)
		(fp_line
			(start 0.700024 1.500124)
			(end -0.700024 1.500124)
			(stroke
				(width 0.1)
				(type default)
			)
			(layer "F.Fab")
		)
		(pad "1" smd rect
			(at -1.150112 -0.94996 270)
			(size 0.6604 0.9652)
			(layers "F.Cu" "F.Mask" "F.Paste")
			(net "GND")
		)
		(pad "2" smd rect
			(at -1.150112 0.94996 270)
			(size 0.6604 0.9652)
			(layers "F.Cu" "F.Mask" "F.Paste")
			(net "PWRGD_P3V3_R1")
		)
		(pad "3" smd rect
			(at 1.150112 0 270)
			(size 0.6604 0.9652)
			(layers "F.Cu" "F.Mask" "F.Paste")
			(net "P3V3")
		)
	)
	(footprint ""
		(layer "F.Cu")
		(at 120.37822 -418.399468 180)
		(property "Reference" "R3317"
			(at 0 0 180)
			(layer "F.SilkS")
			(hide yes)
			(effects
				(font
					(size 1.27 1.27)
				)
			)
		)
		(property "Value" ""
			(at 0 0 180)
			(layer "F.Fab")
			(effects
				(font
					(size 1.27 1.27)
				)
			)
		)
		(duplicate_pad_numbers_are_jumpers no)
		(fp_line
			(start 0.7874 0.4064)
			(end -0.7874 0.4064)
			(stroke
				(width 0.1524)
				(type default)
			)
			(layer "F.SilkS")
		)
		(fp_line
			(start 0.7874 -0.4064)
			(end 0.7874 0.4064)
			(stroke
				(width 0.1524)
				(type default)
			)
			(layer "F.SilkS")
		)
		(fp_line
			(start -0.7874 0.4064)
			(end -0.7874 -0.4064)
			(stroke
				(width 0.1524)
				(type default)
			)
			(layer "F.SilkS")
		)
		(fp_line
			(start -0.7874 -0.4064)
			(end 0.7874 -0.4064)
			(stroke
				(width 0.1524)
				(type default)
			)
			(layer "F.SilkS")
		)
		(fp_line
			(start 0.67945 0.3048)
			(end 0.120396 0.3048)
			(stroke
				(width 0.1)
				(type default)
			)
			(layer "F.Fab")
		)
		(fp_line
			(start 0.67945 -0.3048)
			(end 0.67945 0.3048)
			(stroke
				(width 0.1)
				(type default)
			)
			(layer "F.Fab")
		)
		(fp_line
			(start 0.12065 -0.2794)
			(end 0.12065 -0.3048)
			(stroke
				(width 0.1)
				(type default)
			)
			(layer "F.Fab")
		)
		(fp_line
			(start 0.12065 -0.3048)
			(end 0.67945 -0.3048)
			(stroke
				(width 0.1)
				(type default)
			)
			(layer "F.Fab")
		)
		(fp_line
			(start 0.120396 0.3048)
			(end 0.120396 0.2794)
			(stroke
				(width 0.1)
				(type default)
			)
			(layer "F.Fab")
		)
		(fp_line
			(start 0.120396 0.2794)
			(end -0.12065 0.2794)
			(stroke
				(width 0.1)
				(type default)
			)
			(layer "F.Fab")
		)
		(fp_line
			(start -0.12065 0.3048)
			(end -0.67945 0.3048)
			(stroke
				(width 0.1)
				(type default)
			)
			(layer "F.Fab")
		)
		(fp_line
			(start -0.12065 0.2794)
			(end -0.12065 0.3048)
			(stroke
				(width 0.1)
				(type default)
			)
			(layer "F.Fab")
		)
		(fp_line
			(start -0.12065 -0.2794)
			(end 0.12065 -0.2794)
			(stroke
				(width 0.1)
				(type default)
			)
			(layer "F.Fab")
		)
		(fp_line
			(start -0.12065 -0.305054)
			(end -0.12065 -0.2794)
			(stroke
				(width 0.1)
				(type default)
			)
			(layer "F.Fab")
		)
		(fp_line
			(start -0.67945 0.3048)
			(end -0.67945 -0.305054)
			(stroke
				(width 0.1)
				(type default)
			)
			(layer "F.Fab")
		)
		(fp_line
			(start -0.67945 -0.305054)
			(end -0.12065 -0.305054)
			(stroke
				(width 0.1)
				(type default)
			)
			(layer "F.Fab")
		)
		(pad "1" smd circle
			(at -0.40005 0 180)
			(size 0 0)
			(layers "F.Cu" "F.Mask" "F.Paste")
			(net "P3V3_AUX")
		)
		(pad "2" smd circle
			(at 0.40005 0 180)
			(size 0 0)
			(layers "F.Cu" "F.Mask" "F.Paste")
			(net "GPU_FPGA_RST_R1_BUF_N")
		)
	)
	(footprint ""
		(layer "F.Cu")
		(at 243.03863 -123.004834)
		(property "Reference" "R3201"
			(at 0 0 0)
			(layer "F.SilkS")
			(hide yes)
			(effects
				(font
					(size 1.27 1.27)
				)
			)
		)
		(property "Value" ""
			(at 0 0 0)
			(layer "F.Fab")
			(effects
				(font
					(size 1.27 1.27)
				)
			)
		)
		(duplicate_pad_numbers_are_jumpers no)
		(fp_line
			(start -0.7874 -0.4064)
			(end 0.7874 -0.4064)
			(stroke
				(width 0.1524)
				(type default)
			)
			(layer "F.SilkS")
		)
		(fp_line
			(start -0.7874 0.063754)
			(end -0.7874 -0.4064)
			(stroke
				(width 0.1524)
				(type default)
			)
			(layer "F.SilkS")
		)
		(fp_line
			(start 0.46863 0.4064)
			(end -0.45847 0.4064)
			(stroke
				(width 0.1524)
				(type default)
			)
			(layer "F.SilkS")
		)
		(fp_line
			(start 0.7874 -0.4064)
			(end 0.7874 0.053594)
			(stroke
				(width 0.1524)
				(type default)
			)
			(layer "F.SilkS")
		)
		(fp_line
			(start -0.67945 -0.305054)
			(end -0.12065 -0.305054)
			(stroke
				(width 0.1)
				(type default)
			)
			(layer "F.Fab")
		)
		(fp_line
			(start -0.67945 0.3048)
			(end -0.67945 -0.305054)
			(stroke
				(width 0.1)
				(type default)
			)
			(layer "F.Fab")
		)
		(fp_line
			(start -0.12065 -0.305054)
			(end -0.12065 -0.2794)
			(stroke
				(width 0.1)
				(type default)
			)
			(layer "F.Fab")
		)
		(fp_line
			(start -0.12065 -0.2794)
			(end 0.12065 -0.2794)
			(stroke
				(width 0.1)
				(type default)
			)
			(layer "F.Fab")
		)
		(fp_line
			(start -0.12065 0.2794)
			(end -0.12065 0.3048)
			(stroke
				(width 0.1)
				(type default)
			)
			(layer "F.Fab")
		)
		(fp_line
			(start -0.12065 0.3048)
			(end -0.67945 0.3048)
			(stroke
				(width 0.1)
				(type default)
			)
			(layer "F.Fab")
		)
		(fp_line
			(start 0.120396 0.2794)
			(end -0.12065 0.2794)
			(stroke
				(width 0.1)
				(type default)
			)
			(layer "F.Fab")
		)
		(fp_line
			(start 0.120396 0.3048)
			(end 0.120396 0.2794)
			(stroke
				(width 0.1)
				(type default)
			)
			(layer "F.Fab")
		)
		(fp_line
			(start 0.12065 -0.3048)
			(end 0.67945 -0.3048)
			(stroke
				(width 0.1)
				(type default)
			)
			(layer "F.Fab")
		)
		(fp_line
			(start 0.12065 -0.2794)
			(end 0.12065 -0.3048)
			(stroke
				(width 0.1)
				(type default)
			)
			(layer "F.Fab")
		)
		(fp_line
			(start 0.67945 -0.3048)
			(end 0.67945 0.3048)
			(stroke
				(width 0.1)
				(type default)
			)
			(layer "F.Fab")
		)
		(fp_line
			(start 0.67945 0.3048)
			(end 0.120396 0.3048)
			(stroke
				(width 0.1)
				(type default)
			)
			(layer "F.Fab")
		)
		(pad "1" smd circle
			(at -0.40005 0)
			(size 0 0)
			(layers "F.Cu" "F.Mask" "F.Paste")
			(net "CLK_100M_OCP_V3_2_D_R_DN")
		)
		(pad "2" smd circle
			(at 0.40005 0)
			(size 0 0)
			(layers "F.Cu" "F.Mask" "F.Paste")
			(net "CLK_100M_OCP_V3_2_D_DN")
		)
	)
)
